(kicad_pcb
	(version 20260206)
	(generator "pcbnew")
	(generator_version "10.0")
	(general
		(thickness 1.6)
		(legacy_teardrops no)
	)
	(paper "A4")
	(title_block
		(title "01162023_DA0F0TEBIF0_F0T_Expander_BD_F_brd_V02_OCP.brd")
		(comment 1 "Grand Teton / footprints 6923-6929 of 9728")
	)
	(layers
		(0 "F.Cu" signal "TOP")
		(4 "In1.Cu" signal "GND")
		(6 "In2.Cu" signal "VCC")
		(8 "In3.Cu" signal "VCC1")
		(10 "In4.Cu" signal "GND1")
		(12 "In5.Cu" signal "IN1")
		(14 "In6.Cu" signal "GND2")
		(16 "In7.Cu" signal "IN2")
		(18 "In8.Cu" signal "GND3")
		(20 "In9.Cu" signal "IN3")
		(22 "In10.Cu" signal "GND4")
		(24 "In11.Cu" signal "IN4")
		(26 "In12.Cu" signal "GND5")
		(28 "In13.Cu" signal "IN5")
		(30 "In14.Cu" signal "GND6")
		(32 "In15.Cu" signal "IN6")
		(34 "In16.Cu" signal "GND7")
		(2 "B.Cu" signal "BOTTOM")
		(9 "F.Adhes" user "F.Adhesive")
		(11 "B.Adhes" user "B.Adhesive")
		(13 "F.Paste" user "Package Geometry/Pastemask Top")
		(15 "B.Paste" user "Package Geometry/Pastemask Bottom")
		(5 "F.SilkS" user "Ref Des/Silkscreen Top")
		(7 "B.SilkS" user "Ref Des/Silkscreen Bottom")
		(1 "F.Mask" user "Board Geometry/Soldermask Top")
		(3 "B.Mask" user "Board Geometry/Soldermask Bottom")
		(17 "Dwgs.User" user "User.Drawings")
		(19 "Cmts.User" user "User.Comments")
		(21 "Eco1.User" user "User.Eco1")
		(23 "Eco2.User" user "User.Eco2")
		(25 "Edge.Cuts" user "Board Geometry/Outline")
		(27 "Margin" user)
		(31 "F.CrtYd" user "Package Geometry/Place Bound Top")
		(29 "B.CrtYd" user "Package Geometry/Place Bound Bottom")
		(35 "F.Fab" user "Ref Des/Assembly Top")
		(33 "B.Fab" user "Ref Des/Assembly Bottom")
	)
	(footprint ""
		(layer "F.Cu")
		(at 87.132922 -350.098614 90)
		(property "Reference" "C104"
			(at 0 0 90)
			(layer "F.SilkS")
			(hide yes)
			(effects
				(font
					(size 1.27 1.27)
				)
			)
		)
		(property "Value" ""
			(at 0 0 90)
			(layer "F.Fab")
			(effects
				(font
					(size 1.27 1.27)
				)
			)
		)
		(duplicate_pad_numbers_are_jumpers no)
		(fp_line
			(start 0.299974 -0.150114)
			(end 0.299974 0.150114)
			(stroke
				(width 0.1)
				(type default)
			)
			(layer "F.Fab")
		)
		(fp_line
			(start -0.299974 -0.150114)
			(end 0.299974 -0.150114)
			(stroke
				(width 0.1)
				(type default)
			)
			(layer "F.Fab")
		)
		(fp_line
			(start 0.299974 0.150114)
			(end -0.299974 0.150114)
			(stroke
				(width 0.1)
				(type default)
			)
			(layer "F.Fab")
		)
		(fp_line
			(start -0.299974 0.150114)
			(end -0.299974 -0.150114)
			(stroke
				(width 0.1)
				(type default)
			)
			(layer "F.Fab")
		)
		(pad "1" smd rect
			(at -0.2667 0 90)
			(size 0.3048 0.381)
			(layers "F.Cu" "F.Mask" "F.Paste")
			(net "P5E_PEX0_STN5_TX_DN<92>")
		)
		(pad "2" smd rect
			(at 0.2667 0 90)
			(size 0.3048 0.381)
			(layers "F.Cu" "F.Mask" "F.Paste")
			(net "P5E_PEX0_STN5_TX_C_DN<92>")
		)
	)
	(footprint ""
		(layer "F.Cu")
		(at 152.738328 -108.29544)
		(property "Reference" "C264"
			(at 0 0 0)
			(layer "F.SilkS")
			(hide yes)
			(effects
				(font
					(size 1.27 1.27)
				)
			)
		)
		(property "Value" ""
			(at 0 0 0)
			(layer "F.Fab")
			(effects
				(font
					(size 1.27 1.27)
				)
			)
		)
		(duplicate_pad_numbers_are_jumpers no)
		(fp_line
			(start -0.299974 -0.150114)
			(end 0.299974 -0.150114)
			(stroke
				(width 0.1)
				(type default)
			)
			(layer "F.Fab")
		)
		(fp_line
			(start -0.299974 0.150114)
			(end -0.299974 -0.150114)
			(stroke
				(width 0.1)
				(type default)
			)
			(layer "F.Fab")
		)
		(fp_line
			(start 0.299974 -0.150114)
			(end 0.299974 0.150114)
			(stroke
				(width 0.1)
				(type default)
			)
			(layer "F.Fab")
		)
		(fp_line
			(start 0.299974 0.150114)
			(end -0.299974 0.150114)
			(stroke
				(width 0.1)
				(type default)
			)
			(layer "F.Fab")
		)
		(pad "1" smd rect
			(at -0.2667 0)
			(size 0.3048 0.381)
			(layers "F.Cu" "F.Mask" "F.Paste")
			(net "P5E_PEX1_STN1_TX_DN<21>")
		)
		(pad "2" smd rect
			(at 0.2667 0)
			(size 0.3048 0.381)
			(layers "F.Cu" "F.Mask" "F.Paste")
			(net "P5E_PEX1_STN1_TX_C_DN<21>")
		)
	)
	(footprint ""
		(layer "F.Cu")
		(at 231.954832 -155.960826 -90)
		(property "Reference" "R1208"
			(at 0 0 270)
			(layer "F.SilkS")
			(hide yes)
			(effects
				(font
					(size 1.27 1.27)
				)
			)
		)
		(property "Value" ""
			(at 0 0 270)
			(layer "F.Fab")
			(effects
				(font
					(size 1.27 1.27)
				)
			)
		)
		(duplicate_pad_numbers_are_jumpers no)
		(fp_line
			(start -0.7874 -0.4064)
			(end 0.7874 -0.4064)
			(stroke
				(width 0.1524)
				(type default)
			)
			(layer "F.SilkS")
		)
		(fp_line
			(start -0.67945 0.3048)
			(end -0.67945 -0.305054)
			(stroke
				(width 0.1)
				(type default)
			)
			(layer "F.Fab")
		)
		(fp_line
			(start -0.12065 0.3048)
			(end -0.67945 0.3048)
			(stroke
				(width 0.1)
				(type default)
			)
			(layer "F.Fab")
		)
		(fp_line
			(start 0.120396 0.3048)
			(end 0.120396 0.2794)
			(stroke
				(width 0.1)
				(type default)
			)
			(layer "F.Fab")
		)
		(fp_line
			(start 0.67945 0.3048)
			(end 0.120396 0.3048)
			(stroke
				(width 0.1)
				(type default)
			)
			(layer "F.Fab")
		)
		(fp_line
			(start -0.12065 0.2794)
			(end -0.12065 0.3048)
			(stroke
				(width 0.1)
				(type default)
			)
			(layer "F.Fab")
		)
		(fp_line
			(start 0.120396 0.2794)
			(end -0.12065 0.2794)
			(stroke
				(width 0.1)
				(type default)
			)
			(layer "F.Fab")
		)
		(fp_line
			(start -0.12065 -0.2794)
			(end 0.12065 -0.2794)
			(stroke
				(width 0.1)
				(type default)
			)
			(layer "F.Fab")
		)
		(fp_line
			(start 0.12065 -0.2794)
			(end 0.12065 -0.3048)
			(stroke
				(width 0.1)
				(type default)
			)
			(layer "F.Fab")
		)
		(fp_line
			(start 0.12065 -0.3048)
			(end 0.67945 -0.3048)
			(stroke
				(width 0.1)
				(type default)
			)
			(layer "F.Fab")
		)
		(fp_line
			(start 0.67945 -0.3048)
			(end 0.67945 0.3048)
			(stroke
				(width 0.1)
				(type default)
			)
			(layer "F.Fab")
		)
		(fp_line
			(start -0.67945 -0.305054)
			(end -0.12065 -0.305054)
			(stroke
				(width 0.1)
				(type default)
			)
			(layer "F.Fab")
		)
		(fp_line
			(start -0.12065 -0.305054)
			(end -0.12065 -0.2794)
			(stroke
				(width 0.1)
				(type default)
			)
			(layer "F.Fab")
		)
		(pad "1" smd circle
			(at -0.40005 0 270)
			(size 0 0)
			(layers "F.Cu" "F.Mask" "F.Paste")
			(net "CLK_100M_PEX1_REF_R_DN")
		)
		(pad "2" smd circle
			(at 0.40005 0 270)
			(size 0 0)
			(layers "F.Cu" "F.Mask" "F.Paste")
			(net "CLK_100M_PEX1_REF_DN")
		)
	)
	(footprint ""
		(layer "F.Cu")
		(at 39.582344 -252.356874 -90)
		(property "Reference" "R3954"
			(at 0 0 270)
			(layer "F.SilkS")
			(hide yes)
			(effects
				(font
					(size 1.27 1.27)
				)
			)
		)
		(property "Value" ""
			(at 0 0 270)
			(layer "F.Fab")
			(effects
				(font
					(size 1.27 1.27)
				)
			)
		)
		(duplicate_pad_numbers_are_jumpers no)
		(fp_line
			(start -0.7874 0.4064)
			(end -0.7874 -0.4064)
			(stroke
				(width 0.1524)
				(type default)
			)
			(layer "F.SilkS")
		)
		(fp_line
			(start 0.7874 0.4064)
			(end -0.7874 0.4064)
			(stroke
				(width 0.1524)
				(type default)
			)
			(layer "F.SilkS")
		)
		(fp_line
			(start -0.7874 -0.4064)
			(end 0.7874 -0.4064)
			(stroke
				(width 0.1524)
				(type default)
			)
			(layer "F.SilkS")
		)
		(fp_line
			(start 0.7874 -0.4064)
			(end 0.7874 0.4064)
			(stroke
				(width 0.1524)
				(type default)
			)
			(layer "F.SilkS")
		)
		(fp_line
			(start -0.67945 0.3048)
			(end -0.67945 -0.305054)
			(stroke
				(width 0.1)
				(type default)
			)
			(layer "F.Fab")
		)
		(fp_line
			(start -0.12065 0.3048)
			(end -0.67945 0.3048)
			(stroke
				(width 0.1)
				(type default)
			)
			(layer "F.Fab")
		)
		(fp_line
			(start 0.120396 0.3048)
			(end 0.120396 0.2794)
			(stroke
				(width 0.1)
				(type default)
			)
			(layer "F.Fab")
		)
		(fp_line
			(start 0.67945 0.3048)
			(end 0.120396 0.3048)
			(stroke
				(width 0.1)
				(type default)
			)
			(layer "F.Fab")
		)
		(fp_line
			(start -0.12065 0.2794)
			(end -0.12065 0.3048)
			(stroke
				(width 0.1)
				(type default)
			)
			(layer "F.Fab")
		)
		(fp_line
			(start 0.120396 0.2794)
			(end -0.12065 0.2794)
			(stroke
				(width 0.1)
				(type default)
			)
			(layer "F.Fab")
		)
		(fp_line
			(start -0.12065 -0.2794)
			(end 0.12065 -0.2794)
			(stroke
				(width 0.1)
				(type default)
			)
			(layer "F.Fab")
		)
		(fp_line
			(start 0.12065 -0.2794)
			(end 0.12065 -0.3048)
			(stroke
				(width 0.1)
				(type default)
			)
			(layer "F.Fab")
		)
		(fp_line
			(start 0.12065 -0.3048)
			(end 0.67945 -0.3048)
			(stroke
				(width 0.1)
				(type default)
			)
			(layer "F.Fab")
		)
		(fp_line
			(start 0.67945 -0.3048)
			(end 0.67945 0.3048)
			(stroke
				(width 0.1)
				(type default)
			)
			(layer "F.Fab")
		)
		(fp_line
			(start -0.67945 -0.305054)
			(end -0.12065 -0.305054)
			(stroke
				(width 0.1)
				(type default)
			)
			(layer "F.Fab")
		)
		(fp_line
			(start -0.12065 -0.305054)
			(end -0.12065 -0.2794)
			(stroke
				(width 0.1)
				(type default)
			)
			(layer "F.Fab")
		)
		(pad "1" smd circle
			(at -0.40005 0 270)
			(size 0 0)
			(layers "F.Cu" "F.Mask" "F.Paste")
			(net "PEX0_PCA9555_INT_R_N")
		)
		(pad "2" smd circle
			(at 0.40005 0 270)
			(size 0 0)
			(layers "F.Cu" "F.Mask" "F.Paste")
			(net "P1V8_PEX")
		)
	)
	(footprint ""
		(layer "F.Cu")
		(at 248.094754 -277.535386)
		(property "Reference" "R795"
			(at 0 0 0)
			(layer "F.SilkS")
			(hide yes)
			(effects
				(font
					(size 1.27 1.27)
				)
			)
		)
		(property "Value" ""
			(at 0 0 0)
			(layer "F.Fab")
			(effects
				(font
					(size 1.27 1.27)
				)
			)
		)
		(duplicate_pad_numbers_are_jumpers no)
		(fp_line
			(start -0.7874 -0.4064)
			(end 0.7874 -0.4064)
			(stroke
				(width 0.1524)
				(type default)
			)
			(layer "F.SilkS")
		)
		(fp_line
			(start -0.7874 0.4064)
			(end -0.7874 -0.4064)
			(stroke
				(width 0.1524)
				(type default)
			)
			(layer "F.SilkS")
		)
		(fp_line
			(start 0.7874 -0.4064)
			(end 0.7874 0.4064)
			(stroke
				(width 0.1524)
				(type default)
			)
			(layer "F.SilkS")
		)
		(fp_line
			(start 0.7874 0.4064)
			(end -0.7874 0.4064)
			(stroke
				(width 0.1524)
				(type default)
			)
			(layer "F.SilkS")
		)
		(fp_line
			(start -0.67945 -0.305054)
			(end -0.12065 -0.305054)
			(stroke
				(width 0.1)
				(type default)
			)
			(layer "F.Fab")
		)
		(fp_line
			(start -0.67945 0.3048)
			(end -0.67945 -0.305054)
			(stroke
				(width 0.1)
				(type default)
			)
			(layer "F.Fab")
		)
		(fp_line
			(start -0.12065 -0.305054)
			(end -0.12065 -0.2794)
			(stroke
				(width 0.1)
				(type default)
			)
			(layer "F.Fab")
		)
		(fp_line
			(start -0.12065 -0.2794)
			(end 0.12065 -0.2794)
			(stroke
				(width 0.1)
				(type default)
			)
			(layer "F.Fab")
		)
		(fp_line
			(start -0.12065 0.2794)
			(end -0.12065 0.3048)
			(stroke
				(width 0.1)
				(type default)
			)
			(layer "F.Fab")
		)
		(fp_line
			(start -0.12065 0.3048)
			(end -0.67945 0.3048)
			(stroke
				(width 0.1)
				(type default)
			)
			(layer "F.Fab")
		)
		(fp_line
			(start 0.120396 0.2794)
			(end -0.12065 0.2794)
			(stroke
				(width 0.1)
				(type default)
			)
			(layer "F.Fab")
		)
		(fp_line
			(start 0.120396 0.3048)
			(end 0.120396 0.2794)
			(stroke
				(width 0.1)
				(type default)
			)
			(layer "F.Fab")
		)
		(fp_line
			(start 0.12065 -0.3048)
			(end 0.67945 -0.3048)
			(stroke
				(width 0.1)
				(type default)
			)
			(layer "F.Fab")
		)
		(fp_line
			(start 0.12065 -0.2794)
			(end 0.12065 -0.3048)
			(stroke
				(width 0.1)
				(type default)
			)
			(layer "F.Fab")
		)
		(fp_line
			(start 0.67945 -0.3048)
			(end 0.67945 0.3048)
			(stroke
				(width 0.1)
				(type default)
			)
			(layer "F.Fab")
		)
		(fp_line
			(start 0.67945 0.3048)
			(end 0.120396 0.3048)
			(stroke
				(width 0.1)
				(type default)
			)
			(layer "F.Fab")
		)
		(pad "1" smd circle
			(at -0.40005 0)
			(size 0 0)
			(layers "F.Cu" "F.Mask" "F.Paste")
			(net "PEX2_P1V25_ADC_ALERT_N")
		)
		(pad "2" smd circle
			(at 0.40005 0)
			(size 0 0)
			(layers "F.Cu" "F.Mask" "F.Paste")
			(net "PEX_ADC_ALERT_N")
		)
	)
	(footprint ""
		(layer "F.Cu")
		(at 21.771864 -259.346192)
		(property "Reference" "R1255"
			(at 0 0 0)
			(layer "F.SilkS")
			(hide yes)
			(effects
				(font
					(size 1.27 1.27)
				)
			)
		)
		(property "Value" ""
			(at 0 0 0)
			(layer "F.Fab")
			(effects
				(font
					(size 1.27 1.27)
				)
			)
		)
		(duplicate_pad_numbers_are_jumpers no)
		(fp_line
			(start -0.7874 -0.4064)
			(end 0.7874 -0.4064)
			(stroke
				(width 0.1524)
				(type default)
			)
			(layer "F.SilkS")
		)
		(fp_line
			(start -0.7874 0.4064)
			(end -0.7874 -0.4064)
			(stroke
				(width 0.1524)
				(type default)
			)
			(layer "F.SilkS")
		)
		(fp_line
			(start 0.7874 -0.4064)
			(end 0.7874 0.4064)
			(stroke
				(width 0.1524)
				(type default)
			)
			(layer "F.SilkS")
		)
		(fp_line
			(start 0.7874 0.4064)
			(end -0.7874 0.4064)
			(stroke
				(width 0.1524)
				(type default)
			)
			(layer "F.SilkS")
		)
		(fp_line
			(start -0.67945 -0.305054)
			(end -0.12065 -0.305054)
			(stroke
				(width 0.1)
				(type default)
			)
			(layer "F.Fab")
		)
		(fp_line
			(start -0.67945 0.3048)
			(end -0.67945 -0.305054)
			(stroke
				(width 0.1)
				(type default)
			)
			(layer "F.Fab")
		)
		(fp_line
			(start -0.12065 -0.305054)
			(end -0.12065 -0.2794)
			(stroke
				(width 0.1)
				(type default)
			)
			(layer "F.Fab")
		)
		(fp_line
			(start -0.12065 -0.2794)
			(end 0.12065 -0.2794)
			(stroke
				(width 0.1)
				(type default)
			)
			(layer "F.Fab")
		)
		(fp_line
			(start -0.12065 0.2794)
			(end -0.12065 0.3048)
			(stroke
				(width 0.1)
				(type default)
			)
			(layer "F.Fab")
		)
		(fp_line
			(start -0.12065 0.3048)
			(end -0.67945 0.3048)
			(stroke
				(width 0.1)
				(type default)
			)
			(layer "F.Fab")
		)
		(fp_line
			(start 0.120396 0.2794)
			(end -0.12065 0.2794)
			(stroke
				(width 0.1)
				(type default)
			)
			(layer "F.Fab")
		)
		(fp_line
			(start 0.120396 0.3048)
			(end 0.120396 0.2794)
			(stroke
				(width 0.1)
				(type default)
			)
			(layer "F.Fab")
		)
		(fp_line
			(start 0.12065 -0.3048)
			(end 0.67945 -0.3048)
			(stroke
				(width 0.1)
				(type default)
			)
			(layer "F.Fab")
		)
		(fp_line
			(start 0.12065 -0.2794)
			(end 0.12065 -0.3048)
			(stroke
				(width 0.1)
				(type default)
			)
			(layer "F.Fab")
		)
		(fp_line
			(start 0.67945 -0.3048)
			(end 0.67945 0.3048)
			(stroke
				(width 0.1)
				(type default)
			)
			(layer "F.Fab")
		)
		(fp_line
			(start 0.67945 0.3048)
			(end 0.120396 0.3048)
			(stroke
				(width 0.1)
				(type default)
			)
			(layer "F.Fab")
		)
		(pad "1" smd circle
			(at -0.40005 0)
			(size 0 0)
			(layers "F.Cu" "F.Mask" "F.Paste")
			(net "PEX0_SYS_ERR_N")
		)
		(pad "2" smd circle
			(at 0.40005 0)
			(size 0 0)
			(layers "F.Cu" "F.Mask" "F.Paste")
			(net "PEX0_SYS_ERR_R_N")
		)
	)
	(footprint ""
		(layer "F.Cu")
		(at 366.955578 -84.927694 180)
		(property "Reference" "R1622"
			(at 0 0 180)
			(layer "F.SilkS")
			(hide yes)
			(effects
				(font
					(size 1.27 1.27)
				)
			)
		)
		(property "Value" ""
			(at 0 0 180)
			(layer "F.Fab")
			(effects
				(font
					(size 1.27 1.27)
				)
			)
		)
		(duplicate_pad_numbers_are_jumpers no)
		(fp_line
			(start 0.7874 0.4064)
			(end -0.7874 0.4064)
			(stroke
				(width 0.1524)
				(type default)
			)
			(layer "F.SilkS")
		)
		(fp_line
			(start 0.7874 -0.4064)
			(end 0.7874 0.4064)
			(stroke
				(width 0.1524)
				(type default)
			)
			(layer "F.SilkS")
		)
		(fp_line
			(start -0.7874 0.4064)
			(end -0.7874 -0.4064)
			(stroke
				(width 0.1524)
				(type default)
			)
			(layer "F.SilkS")
		)
		(fp_line
			(start -0.7874 -0.4064)
			(end 0.7874 -0.4064)
			(stroke
				(width 0.1524)
				(type default)
			)
			(layer "F.SilkS")
		)
		(fp_line
			(start 0.67945 0.3048)
			(end 0.120396 0.3048)
			(stroke
				(width 0.1)
				(type default)
			)
			(layer "F.Fab")
		)
		(fp_line
			(start 0.67945 -0.3048)
			(end 0.67945 0.3048)
			(stroke
				(width 0.1)
				(type default)
			)
			(layer "F.Fab")
		)
		(fp_line
			(start 0.12065 -0.2794)
			(end 0.12065 -0.3048)
			(stroke
				(width 0.1)
				(type default)
			)
			(layer "F.Fab")
		)
		(fp_line
			(start 0.12065 -0.3048)
			(end 0.67945 -0.3048)
			(stroke
				(width 0.1)
				(type default)
			)
			(layer "F.Fab")
		)
		(fp_line
			(start 0.120396 0.3048)
			(end 0.120396 0.2794)
			(stroke
				(width 0.1)
				(type default)
			)
			(layer "F.Fab")
		)
		(fp_line
			(start 0.120396 0.2794)
			(end -0.12065 0.2794)
			(stroke
				(width 0.1)
				(type default)
			)
			(layer "F.Fab")
		)
		(fp_line
			(start -0.12065 0.3048)
			(end -0.67945 0.3048)
			(stroke
				(width 0.1)
				(type default)
			)
			(layer "F.Fab")
		)
		(fp_line
			(start -0.12065 0.2794)
			(end -0.12065 0.3048)
			(stroke
				(width 0.1)
				(type default)
			)
			(layer "F.Fab")
		)
		(fp_line
			(start -0.12065 -0.2794)
			(end 0.12065 -0.2794)
			(stroke
				(width 0.1)
				(type default)
			)
			(layer "F.Fab")
		)
		(fp_line
			(start -0.12065 -0.305054)
			(end -0.12065 -0.2794)
			(stroke
				(width 0.1)
				(type default)
			)
			(layer "F.Fab")
		)
		(fp_line
			(start -0.67945 0.3048)
			(end -0.67945 -0.305054)
			(stroke
				(width 0.1)
				(type default)
			)
			(layer "F.Fab")
		)
		(fp_line
			(start -0.67945 -0.305054)
			(end -0.12065 -0.305054)
			(stroke
				(width 0.1)
				(type default)
			)
			(layer "F.Fab")
		)
		(pad "1" smd circle
			(at -0.40005 0 180)
			(size 0 0)
			(layers "F.Cu" "F.Mask" "F.Paste")
			(net "SMB_BIC_I2C9_MUX1_SSD13_R_SCL")
		)
		(pad "2" smd circle
			(at 0.40005 0 180)
			(size 0 0)
			(layers "F.Cu" "F.Mask" "F.Paste")
			(net "SMB_BIC_I2C9_MUX1_SSD13_SCL")
		)
	)
)
